(kicad_pcb
	(version 20260206)
	(generator "pcbnew")
	(generator_version "10.0")
	(general
		(thickness 1.6)
		(legacy_teardrops no)
	)
	(paper "A4")
	(title_block
		(title "Bryce Canyon_IOM_IOC_16318-2_OCP.brd")
		(comment 1 "Bryce Canyon / footprints 391-398 of 1605")
	)
	(layers
		(0 "F.Cu" signal "TOP")
		(4 "In1.Cu" signal "L2GND")
		(6 "In2.Cu" signal "L3")
		(8 "In3.Cu" signal "L4VCC")
		(10 "In4.Cu" signal "L5VCC")
		(12 "In5.Cu" signal "L6")
		(14 "In6.Cu" signal "L7GND")
		(2 "B.Cu" signal "BOTTOM")
		(9 "F.Adhes" user "F.Adhesive")
		(11 "B.Adhes" user "B.Adhesive")
		(13 "F.Paste" user "Package Geometry/Pastemask Top")
		(15 "B.Paste" user "Package Geometry/Pastemask Bottom")
		(5 "F.SilkS" user "Ref Des/Silkscreen Top")
		(7 "B.SilkS" user "Ref Des/Silkscreen Bottom")
		(1 "F.Mask" user "Board Geometry/Soldermask Top")
		(3 "B.Mask" user "Board Geometry/Soldermask Bottom")
		(17 "Dwgs.User" user "User.Drawings")
		(19 "Cmts.User" user "User.Comments")
		(21 "Eco1.User" user "User.Eco1")
		(23 "Eco2.User" user "User.Eco2")
		(25 "Edge.Cuts" user "Board Geometry/Outline")
		(27 "Margin" user)
		(31 "F.CrtYd" user "Package Geometry/Place Bound Top")
		(29 "B.CrtYd" user "Package Geometry/Place Bound Bottom")
		(35 "F.Fab" user "Ref Des/Assembly Top")
		(33 "B.Fab" user "Ref Des/Assembly Bottom")
	)
	(footprint ""
		(layer "F.Cu")
		(at 197.358 -124.6632 180)
		(property "Reference" "R555"
			(at 0 0 180)
			(layer "F.SilkS")
			(hide yes)
			(effects
				(font
					(size 1.27 1.27)
				)
			)
		)
		(property "Value" "221R2F-2-GP"
			(at 0.064008 -3.993896 180)
			(unlocked yes)
			(layer "F.Fab")
			(hide yes)
			(effects
				(font
					(size 1.016 1.016)
					(thickness 0.1524)
				)
			)
		)
		(property "Device Type" "R402H16"
			(at 0.064008 -5.517896 180)
			(unlocked yes)
			(layer "F.Fab")
			(hide yes)
			(effects
				(font
					(size 1.016 1.016)
					(thickness 0.1524)
				)
			)
		)
		(duplicate_pad_numbers_are_jumpers no)
		(fp_line
			(start 0.508 -0.9398)
			(end -0.508 -0.9398)
			(stroke
				(width 0.1524)
				(type default)
			)
			(layer "F.SilkS")
		)
		(fp_line
			(start -0.508 -0.9398)
			(end -0.508 0.9398)
			(stroke
				(width 0.1524)
				(type default)
			)
			(layer "F.SilkS")
		)
		(fp_rect
			(start -0.508 0.9398)
			(end 0.508 -0.9398)
			(stroke
				(width 0)
				(type default)
			)
			(fill no)
			(layer "F.CrtYd")
		)
		(fp_rect
			(start -0.508 0.9398)
			(end 0.508 -0.9398)
			(stroke
				(width 0)
				(type default)
			)
			(fill no)
			(layer "F.Fab")
		)
		(pad "1" smd custom
			(at 0 -0.4445 180)
			(size 0.1397 0.1397)
			(layers "F.Cu" "F.Mask" "F.Paste")
			(net "VT235_VFB")
			(options
				(clearance outline)
				(anchor circle)
			)
			(primitives
				(gr_poly
					(pts
						(arc
							(start -0.1778 -0.2794)
							(mid -0.249642 -0.249642)
							(end -0.2794 -0.1778)
						)
						(arc
							(start -0.2794 0.1778)
							(mid -0.249642 0.249642)
							(end -0.1778 0.2794)
						)
						(arc
							(start 0.1778 0.2794)
							(mid 0.249642 0.249642)
							(end 0.2794 0.1778)
						)
						(arc
							(start 0.2794 -0.1778)
							(mid 0.249642 -0.249642)
							(end 0.1778 -0.2794)
						)
					)
					(width 0)
					(fill yes)
				)
			)
		)
		(pad "2" smd custom
			(at 0 0.4445 180)
			(size 0.1397 0.1397)
			(layers "F.Cu" "F.Mask" "F.Paste")
			(net "P0V975_SEN")
			(options
				(clearance outline)
				(anchor circle)
			)
			(primitives
				(gr_poly
					(pts
						(arc
							(start -0.1778 -0.2794)
							(mid -0.249642 -0.249642)
							(end -0.2794 -0.1778)
						)
						(arc
							(start -0.2794 0.1778)
							(mid -0.249642 0.249642)
							(end -0.1778 0.2794)
						)
						(arc
							(start 0.1778 0.2794)
							(mid 0.249642 0.249642)
							(end 0.2794 0.1778)
						)
						(arc
							(start 0.2794 -0.1778)
							(mid 0.249642 -0.249642)
							(end 0.1778 -0.2794)
						)
					)
					(width 0)
					(fill yes)
				)
			)
		)
	)
	(footprint ""
		(layer "F.Cu")
		(at 48.703484 -166.456868 180)
		(property "Reference" "R779"
			(at 0 0 180)
			(layer "F.SilkS")
			(hide yes)
			(effects
				(font
					(size 1.27 1.27)
				)
			)
		)
		(property "Value" "1KR2F-3-GP"
			(at 0.064008 -3.993896 180)
			(unlocked yes)
			(layer "F.Fab")
			(hide yes)
			(effects
				(font
					(size 1.016 1.016)
					(thickness 0.1524)
				)
			)
		)
		(property "Device Type" "R402H16"
			(at 0.064008 -5.517896 180)
			(unlocked yes)
			(layer "F.Fab")
			(hide yes)
			(effects
				(font
					(size 1.016 1.016)
					(thickness 0.1524)
				)
			)
		)
		(duplicate_pad_numbers_are_jumpers no)
		(fp_line
			(start 0.508 -0.9398)
			(end -0.508 -0.9398)
			(stroke
				(width 0.1524)
				(type default)
			)
			(layer "F.SilkS")
		)
		(fp_line
			(start -0.508 -0.9398)
			(end -0.508 0.9398)
			(stroke
				(width 0.1524)
				(type default)
			)
			(layer "F.SilkS")
		)
		(fp_rect
			(start -0.508 0.9398)
			(end 0.508 -0.9398)
			(stroke
				(width 0)
				(type default)
			)
			(fill no)
			(layer "F.CrtYd")
		)
		(fp_rect
			(start -0.508 0.9398)
			(end 0.508 -0.9398)
			(stroke
				(width 0)
				(type default)
			)
			(fill no)
			(layer "F.Fab")
		)
		(pad "1" smd custom
			(at 0 -0.4445 180)
			(size 0.1397 0.1397)
			(layers "F.Cu" "F.Mask" "F.Paste")
			(net "ADC_P2V5_STBY")
			(options
				(clearance outline)
				(anchor circle)
			)
			(primitives
				(gr_poly
					(pts
						(arc
							(start -0.1778 -0.2794)
							(mid -0.249642 -0.249642)
							(end -0.2794 -0.1778)
						)
						(arc
							(start -0.2794 0.1778)
							(mid -0.249642 0.249642)
							(end -0.1778 0.2794)
						)
						(arc
							(start 0.1778 0.2794)
							(mid 0.249642 0.249642)
							(end 0.2794 0.1778)
						)
						(arc
							(start 0.2794 -0.1778)
							(mid 0.249642 -0.249642)
							(end 0.1778 -0.2794)
						)
					)
					(width 0)
					(fill yes)
				)
			)
		)
		(pad "2" smd custom
			(at 0 0.4445 180)
			(size 0.1397 0.1397)
			(layers "F.Cu" "F.Mask" "F.Paste")
			(net "GND")
			(options
				(clearance outline)
				(anchor circle)
			)
			(primitives
				(gr_poly
					(pts
						(arc
							(start -0.1778 -0.2794)
							(mid -0.249642 -0.249642)
							(end -0.2794 -0.1778)
						)
						(arc
							(start -0.2794 0.1778)
							(mid -0.249642 0.249642)
							(end -0.1778 0.2794)
						)
						(arc
							(start 0.1778 0.2794)
							(mid 0.249642 0.249642)
							(end 0.2794 0.1778)
						)
						(arc
							(start 0.2794 -0.1778)
							(mid 0.249642 -0.249642)
							(end 0.1778 -0.2794)
						)
					)
					(width 0)
					(fill yes)
				)
			)
		)
	)
	(footprint ""
		(layer "F.Cu")
		(at 124.841 -6.604 -90)
		(property "Reference" "R711"
			(at 0 0 270)
			(layer "F.SilkS")
			(hide yes)
			(effects
				(font
					(size 1.27 1.27)
				)
			)
		)
		(property "Value" "0R2J-2-GP"
			(at 0.064008 -3.993896 270)
			(unlocked yes)
			(layer "F.Fab")
			(hide yes)
			(effects
				(font
					(size 1.016 1.016)
					(thickness 0.1524)
				)
			)
		)
		(property "Device Type" "R402H16"
			(at 0.064008 -5.517896 270)
			(unlocked yes)
			(layer "F.Fab")
			(hide yes)
			(effects
				(font
					(size 1.016 1.016)
					(thickness 0.1524)
				)
			)
		)
		(duplicate_pad_numbers_are_jumpers no)
		(fp_line
			(start -0.508 -0.9398)
			(end -0.508 0.9398)
			(stroke
				(width 0.1524)
				(type default)
			)
			(layer "F.SilkS")
		)
		(fp_line
			(start 0.508 -0.9398)
			(end -0.508 -0.9398)
			(stroke
				(width 0.1524)
				(type default)
			)
			(layer "F.SilkS")
		)
		(fp_rect
			(start -0.508 0.9398)
			(end 0.508 -0.9398)
			(stroke
				(width 0)
				(type default)
			)
			(fill no)
			(layer "F.CrtYd")
		)
		(fp_rect
			(start -0.508 0.9398)
			(end 0.508 -0.9398)
			(stroke
				(width 0)
				(type default)
			)
			(fill no)
			(layer "F.Fab")
		)
		(pad "1" smd custom
			(at 0 -0.4445 270)
			(size 0.1397 0.1397)
			(layers "F.Cu" "F.Mask" "F.Paste")
			(net "I2C_IOM_SCL")
			(options
				(clearance outline)
				(anchor circle)
			)
			(primitives
				(gr_poly
					(pts
						(arc
							(start -0.1778 -0.2794)
							(mid -0.249642 -0.249642)
							(end -0.2794 -0.1778)
						)
						(arc
							(start -0.2794 0.1778)
							(mid -0.249642 0.249642)
							(end -0.1778 0.2794)
						)
						(arc
							(start 0.1778 0.2794)
							(mid 0.249642 0.249642)
							(end 0.2794 0.1778)
						)
						(arc
							(start 0.2794 -0.1778)
							(mid 0.249642 -0.249642)
							(end 0.1778 -0.2794)
						)
					)
					(width 0)
					(fill yes)
				)
			)
		)
		(pad "2" smd custom
			(at 0 0.4445 270)
			(size 0.1397 0.1397)
			(layers "F.Cu" "F.Mask" "F.Paste")
			(net "HSW_SCL")
			(options
				(clearance outline)
				(anchor circle)
			)
			(primitives
				(gr_poly
					(pts
						(arc
							(start -0.1778 -0.2794)
							(mid -0.249642 -0.249642)
							(end -0.2794 -0.1778)
						)
						(arc
							(start -0.2794 0.1778)
							(mid -0.249642 0.249642)
							(end -0.1778 0.2794)
						)
						(arc
							(start 0.1778 0.2794)
							(mid 0.249642 0.249642)
							(end 0.2794 0.1778)
						)
						(arc
							(start 0.2794 -0.1778)
							(mid 0.249642 -0.249642)
							(end 0.1778 -0.2794)
						)
					)
					(width 0)
					(fill yes)
				)
			)
		)
	)
	(footprint ""
		(layer "F.Cu")
		(at 17.99971 -119.99976)
		(property "Reference" ""
			(at 0 0 0)
			(layer "F.SilkS")
			(hide yes)
			(effects
				(font
					(size 1.27 1.27)
				)
			)
		)
		(property "Value" "*"
			(at -6.38175 0.19685 0)
			(unlocked yes)
			(layer "F.Fab")
			(hide yes)
			(effects
				(font
					(size 1.016 1.016)
					(thickness 0.1524)
				)
			)
		)
		(duplicate_pad_numbers_are_jumpers no)
		(fp_poly
			(pts
				(arc
					(start 5.0673 0)
					(mid -5.0673 0)
					(end 5.0673 0)
				)
			)
			(stroke
				(width 0)
				(type default)
			)
			(fill no)
			(layer "B.CrtYd")
		)
		(fp_poly
			(pts
				(arc
					(start 5.0673 0)
					(mid -5.0673 0)
					(end 5.0673 0)
				)
			)
			(stroke
				(width 0)
				(type default)
			)
			(fill no)
			(layer "F.CrtYd")
		)
		(fp_poly
			(pts
				(arc
					(start 5.0673 0)
					(mid -5.0673 0)
					(end 5.0673 0)
				)
			)
			(stroke
				(width 0)
				(type default)
			)
			(fill no)
			(layer "B.Fab")
		)
		(fp_poly
			(pts
				(arc
					(start 5.0673 0)
					(mid -5.0673 0)
					(end 5.0673 0)
				)
			)
			(stroke
				(width 0)
				(type default)
			)
			(fill no)
			(layer "F.Fab")
		)
		(pad "1" thru_hole circle
			(at 0 0)
			(size 9.525 9.525)
			(drill 3.5052)
			(layers "*.Cu" "*.Mask")
			(remove_unused_layers no)
			(net "Net_7")
			(clearance -2.5019)
			(thermal_gap 0.3048)
			(padstack
				(mode front_inner_back)
				(layer "Inner"
					(shape circle)
					(size 3.9116 3.9116)
					(clearance 0.3048)
				)
				(layer "B.Cu"
					(shape circle)
					(size 9.525 9.525)
					(clearance -2.5019)
				)
			)
		)
	)
	(footprint ""
		(layer "F.Cu")
		(at 208.055972 -72.7964 90)
		(property "Reference" "C312"
			(at 0 0 90)
			(layer "F.SilkS")
			(hide yes)
			(effects
				(font
					(size 1.27 1.27)
				)
			)
		)
		(property "Value" "SCD01U16V1KX-GP"
			(at -2.8321 -1.7399 90)
			(unlocked yes)
			(layer "F.Fab")
			(hide yes)
			(effects
				(font
					(size 1.016 1.016)
					(thickness 0.1524)
				)
			)
		)
		(property "Device Type" "C0201H13"
			(at -2.8321 -3.2639 90)
			(unlocked yes)
			(layer "F.Fab")
			(hide yes)
			(effects
				(font
					(size 1.016 1.016)
					(thickness 0.1524)
				)
			)
		)
		(duplicate_pad_numbers_are_jumpers no)
		(fp_rect
			(start -0.2794 0.6477)
			(end 0.2794 -0.6477)
			(stroke
				(width 0)
				(type default)
			)
			(fill no)
			(layer "F.CrtYd")
		)
		(fp_rect
			(start -0.2794 0.6477)
			(end 0.2794 -0.6477)
			(stroke
				(width 0)
				(type default)
			)
			(fill no)
			(layer "F.Fab")
		)
		(pad "1" smd custom
			(at 0 -0.2794 90)
			(size 0.0762 0.0762)
			(layers "F.Cu" "F.Mask" "F.Paste")
			(net "PHY_IOC_TO_CON_A_2_DN_C")
			(options
				(clearance outline)
				(anchor circle)
			)
			(primitives
				(gr_poly
					(pts
						(arc
							(start 0.1524 -0.127)
							(mid 0.137521 -0.162921)
							(end 0.1016 -0.1778)
						)
						(arc
							(start -0.1016 -0.1778)
							(mid -0.137521 -0.162921)
							(end -0.1524 -0.127)
						)
						(arc
							(start -0.1524 0.127)
							(mid -0.137521 0.162921)
							(end -0.1016 0.1778)
						)
						(arc
							(start 0.1016 0.1778)
							(mid 0.137521 0.162921)
							(end 0.1524 0.127)
						)
					)
					(width 0)
					(fill yes)
				)
			)
		)
		(pad "2" smd custom
			(at 0 0.2794 90)
			(size 0.0762 0.0762)
			(layers "F.Cu" "F.Mask" "F.Paste")
			(net "PHY_IOC_TO_CON_A_2_DN")
			(options
				(clearance outline)
				(anchor circle)
			)
			(primitives
				(gr_poly
					(pts
						(arc
							(start 0.1524 -0.127)
							(mid 0.137521 -0.162921)
							(end 0.1016 -0.1778)
						)
						(arc
							(start -0.1016 -0.1778)
							(mid -0.137521 -0.162921)
							(end -0.1524 -0.127)
						)
						(arc
							(start -0.1524 0.127)
							(mid -0.137521 0.162921)
							(end -0.1016 0.1778)
						)
						(arc
							(start 0.1016 0.1778)
							(mid 0.137521 0.162921)
							(end 0.1524 0.127)
						)
					)
					(width 0)
					(fill yes)
				)
			)
		)
	)
	(footprint ""
		(layer "F.Cu")
		(at 197.0532 -16.764 90)
		(property "Reference" "C516"
			(at 0 0 90)
			(layer "F.SilkS")
			(hide yes)
			(effects
				(font
					(size 1.27 1.27)
				)
			)
		)
		(property "Value" "SCD1U16V2KX-3GP"
			(at 1.1811 -2.7051 90)
			(unlocked yes)
			(layer "F.Fab")
			(hide yes)
			(effects
				(font
					(size 1.016 1.016)
					(thickness 0.1524)
				)
			)
		)
		(property "Device Type" "C402H22"
			(at 1.1811 -4.2291 90)
			(unlocked yes)
			(layer "F.Fab")
			(hide yes)
			(effects
				(font
					(size 1.016 1.016)
					(thickness 0.1524)
				)
			)
		)
		(duplicate_pad_numbers_are_jumpers no)
		(fp_rect
			(start -0.4318 0.9525)
			(end 0.4318 -0.9525)
			(stroke
				(width 0)
				(type default)
			)
			(fill no)
			(layer "F.CrtYd")
		)
		(fp_rect
			(start -0.4318 0.9525)
			(end 0.4318 -0.9525)
			(stroke
				(width 0)
				(type default)
			)
			(fill no)
			(layer "F.Fab")
		)
		(pad "1" smd custom
			(at 0 -0.4445 90)
			(size 0.1524 0.1524)
			(layers "F.Cu" "F.Mask" "F.Paste")
			(net "P3V3_STBY")
			(options
				(clearance outline)
				(anchor circle)
			)
			(primitives
				(gr_poly
					(pts
						(arc
							(start 0.3048 -0.2032)
							(mid 0.275042 -0.275042)
							(end 0.2032 -0.3048)
						)
						(arc
							(start -0.2032 -0.3048)
							(mid -0.275042 -0.275042)
							(end -0.3048 -0.2032)
						)
						(arc
							(start -0.3048 0.2032)
							(mid -0.275042 0.275042)
							(end -0.2032 0.3048)
						)
						(arc
							(start 0.2032 0.3048)
							(mid 0.275042 0.275042)
							(end 0.3048 0.2032)
						)
					)
					(width 0)
					(fill yes)
				)
			)
		)
		(pad "2" smd custom
			(at 0 0.4445 90)
			(size 0.1524 0.1524)
			(layers "F.Cu" "F.Mask" "F.Paste")
			(net "GND")
			(options
				(clearance outline)
				(anchor circle)
			)
			(primitives
				(gr_poly
					(pts
						(arc
							(start 0.3048 -0.2032)
							(mid 0.275042 -0.275042)
							(end 0.2032 -0.3048)
						)
						(arc
							(start -0.2032 -0.3048)
							(mid -0.275042 -0.275042)
							(end -0.3048 -0.2032)
						)
						(arc
							(start -0.3048 0.2032)
							(mid -0.275042 0.275042)
							(end -0.2032 0.3048)
						)
						(arc
							(start 0.2032 0.3048)
							(mid 0.275042 0.275042)
							(end 0.3048 0.2032)
						)
					)
					(width 0)
					(fill yes)
				)
			)
		)
	)
	(footprint ""
		(layer "F.Cu")
		(at 75.81138 -186.683396 180)
		(property "Reference" "C199"
			(at 0 0 180)
			(layer "F.SilkS")
			(hide yes)
			(effects
				(font
					(size 1.27 1.27)
				)
			)
		)
		(property "Value" "SC10U6D3V5KX-4GP"
			(at -0.0762 -6.1214 180)
			(unlocked yes)
			(layer "F.Fab")
			(hide yes)
			(effects
				(font
					(size 1.016 1.016)
					(thickness 0.1524)
				)
			)
		)
		(property "Device Type" "C805H58"
			(at -0.0762 -8.1534 180)
			(unlocked yes)
			(layer "F.Fab")
			(hide yes)
			(effects
				(font
					(size 1.016 1.016)
					(thickness 0.1524)
				)
			)
		)
		(duplicate_pad_numbers_are_jumpers no)
		(fp_line
			(start 0.635 0)
			(end -0.635 0)
			(stroke
				(width 0.508)
				(type default)
			)
			(layer "F.SilkS")
		)
		(fp_rect
			(start -0.9652 1.778)
			(end 0.9652 -1.778)
			(stroke
				(width 0)
				(type default)
			)
			(fill no)
			(layer "F.CrtYd")
		)
		(fp_poly
			(pts
				(xy -0.9652 -1.778) (xy 0.9652 -1.778) (xy 0.9652 1.778) (xy -0.9652 1.778)
			)
			(stroke
				(width 0)
				(type default)
			)
			(fill no)
			(layer "F.Fab")
		)
		(pad "1" smd rect
			(at 0 -0.9652 180)
			(size 1.397 1.143)
			(layers "F.Cu" "F.Mask" "F.Paste")
			(net "P3V3_STBY")
		)
		(pad "2" smd rect
			(at 0 0.9652 180)
			(size 1.397 1.143)
			(layers "F.Cu" "F.Mask" "F.Paste")
			(net "GND")
		)
	)
	(footprint ""
		(layer "F.Cu")
		(at 72.04964 -163.6395 -90)
		(property "Reference" "C245"
			(at 0 0 270)
			(layer "F.SilkS")
			(hide yes)
			(effects
				(font
					(size 1.27 1.27)
				)
			)
		)
		(property "Value" "SCD1U16V2KX-3GP"
			(at 1.1811 -2.7051 270)
			(unlocked yes)
			(layer "F.Fab")
			(hide yes)
			(effects
				(font
					(size 1.016 1.016)
					(thickness 0.1524)
				)
			)
		)
		(property "Device Type" "C402H22"
			(at 1.1811 -4.2291 270)
			(unlocked yes)
			(layer "F.Fab")
			(hide yes)
			(effects
				(font
					(size 1.016 1.016)
					(thickness 0.1524)
				)
			)
		)
		(duplicate_pad_numbers_are_jumpers no)
		(fp_rect
			(start -0.4318 0.9525)
			(end 0.4318 -0.9525)
			(stroke
				(width 0)
				(type default)
			)
			(fill no)
			(layer "F.CrtYd")
		)
		(fp_rect
			(start -0.4318 0.9525)
			(end 0.4318 -0.9525)
			(stroke
				(width 0)
				(type default)
			)
			(fill no)
			(layer "F.Fab")
		)
		(pad "1" smd custom
			(at 0 -0.4445 270)
			(size 0.1524 0.1524)
			(layers "F.Cu" "F.Mask" "F.Paste")
			(net "TPS74801_P1V15_STBY_EN")
			(options
				(clearance outline)
				(anchor circle)
			)
			(primitives
				(gr_poly
					(pts
						(arc
							(start 0.3048 -0.2032)
							(mid 0.275042 -0.275042)
							(end 0.2032 -0.3048)
						)
						(arc
							(start -0.2032 -0.3048)
							(mid -0.275042 -0.275042)
							(end -0.3048 -0.2032)
						)
						(arc
							(start -0.3048 0.2032)
							(mid -0.275042 0.275042)
							(end -0.2032 0.3048)
						)
						(arc
							(start 0.2032 0.3048)
							(mid 0.275042 0.275042)
							(end 0.3048 0.2032)
						)
					)
					(width 0)
					(fill yes)
				)
			)
		)
		(pad "2" smd custom
			(at 0 0.4445 270)
			(size 0.1524 0.1524)
			(layers "F.Cu" "F.Mask" "F.Paste")
			(net "GND")
			(options
				(clearance outline)
				(anchor circle)
			)
			(primitives
				(gr_poly
					(pts
						(arc
							(start 0.3048 -0.2032)
							(mid 0.275042 -0.275042)
							(end 0.2032 -0.3048)
						)
						(arc
							(start -0.2032 -0.3048)
							(mid -0.275042 -0.275042)
							(end -0.3048 -0.2032)
						)
						(arc
							(start -0.3048 0.2032)
							(mid -0.275042 0.275042)
							(end -0.2032 0.3048)
						)
						(arc
							(start 0.2032 0.3048)
							(mid 0.275042 0.275042)
							(end 0.3048 0.2032)
						)
					)
					(width 0)
					(fill yes)
				)
			)
		)
	)
)
